(kicad_pcb
	(version 20260206)
	(generator "pcbnew")
	(generator_version "10.0")
	(general
		(thickness 1.6)
		(legacy_teardrops no)
	)
	(paper "A4")
	(title_block
		(title "Bryce Canyon_F.DPB_16315-1-OCP.brd")
		(comment 1 "Bryce Canyon / footprints 608-614 of 2223")
	)
	(layers
		(0 "F.Cu" signal "TOP")
		(4 "In1.Cu" signal "L2GND")
		(6 "In2.Cu" signal "L3")
		(8 "In3.Cu" signal "L4GND")
		(10 "In4.Cu" signal "L5")
		(12 "In5.Cu" signal "L6VCC")
		(14 "In6.Cu" signal "L7VCC")
		(16 "In7.Cu" signal "L8")
		(18 "In8.Cu" signal "L9GND")
		(20 "In9.Cu" signal "L10")
		(22 "In10.Cu" signal "L11GND")
		(2 "B.Cu" signal "BOTTOM")
		(9 "F.Adhes" user "F.Adhesive")
		(11 "B.Adhes" user "B.Adhesive")
		(13 "F.Paste" user "Package Geometry/Pastemask Top")
		(15 "B.Paste" user "Package Geometry/Pastemask Bottom")
		(5 "F.SilkS" user "Ref Des/Silkscreen Top")
		(7 "B.SilkS" user "Ref Des/Silkscreen Bottom")
		(1 "F.Mask" user "Board Geometry/Soldermask Top")
		(3 "B.Mask" user "Board Geometry/Soldermask Bottom")
		(17 "Dwgs.User" user "User.Drawings")
		(19 "Cmts.User" user "User.Comments")
		(21 "Eco1.User" user "User.Eco1")
		(23 "Eco2.User" user "User.Eco2")
		(25 "Edge.Cuts" user "Board Geometry/Outline")
		(27 "Margin" user)
		(31 "F.CrtYd" user "Package Geometry/Place Bound Top")
		(29 "B.CrtYd" user "Package Geometry/Place Bound Bottom")
		(35 "F.Fab" user "Ref Des/Assembly Top")
		(33 "B.Fab" user "Ref Des/Assembly Bottom")
	)
	(footprint ""
		(layer "F.Cu")
		(at 311.898538 -290.91255 90)
		(property "Reference" "R587"
			(at 0 0 90)
			(layer "F.SilkS")
			(hide yes)
			(effects
				(font
					(size 1.27 1.27)
				)
			)
		)
		(property "Value" "4K7R2J-2-GP"
			(at 0.064008 -3.993896 90)
			(unlocked yes)
			(layer "F.Fab")
			(hide yes)
			(effects
				(font
					(size 1.016 1.016)
					(thickness 0.1524)
				)
			)
		)
		(property "Device Type" "R402H16"
			(at 0.064008 -5.517896 90)
			(unlocked yes)
			(layer "F.Fab")
			(hide yes)
			(effects
				(font
					(size 1.016 1.016)
					(thickness 0.1524)
				)
			)
		)
		(duplicate_pad_numbers_are_jumpers no)
		(fp_line
			(start 0.508 -0.9398)
			(end -0.508 -0.9398)
			(stroke
				(width 0.1524)
				(type default)
			)
			(layer "F.SilkS")
		)
		(fp_line
			(start -0.508 -0.9398)
			(end -0.508 0.9398)
			(stroke
				(width 0.1524)
				(type default)
			)
			(layer "F.SilkS")
		)
		(fp_rect
			(start -0.508 0.9398)
			(end 0.508 -0.9398)
			(stroke
				(width 0)
				(type default)
			)
			(fill no)
			(layer "F.CrtYd")
		)
		(fp_rect
			(start -0.508 0.9398)
			(end 0.508 -0.9398)
			(stroke
				(width 0)
				(type default)
			)
			(fill no)
			(layer "F.Fab")
		)
		(pad "1" smd custom
			(at 0 -0.4445 90)
			(size 0.1397 0.1397)
			(layers "F.Cu" "F.Mask" "F.Paste")
			(net "DRIVE_B_30_FLT_LED")
			(options
				(clearance outline)
				(anchor circle)
			)
			(primitives
				(gr_poly
					(pts
						(arc
							(start -0.1778 -0.2794)
							(mid -0.249642 -0.249642)
							(end -0.2794 -0.1778)
						)
						(arc
							(start -0.2794 0.1778)
							(mid -0.249642 0.249642)
							(end -0.1778 0.2794)
						)
						(arc
							(start 0.1778 0.2794)
							(mid 0.249642 0.249642)
							(end 0.2794 0.1778)
						)
						(arc
							(start 0.2794 -0.1778)
							(mid 0.249642 -0.249642)
							(end 0.1778 -0.2794)
						)
					)
					(width 0)
					(fill yes)
				)
			)
		)
		(pad "2" smd custom
			(at 0 0.4445 90)
			(size 0.1397 0.1397)
			(layers "F.Cu" "F.Mask" "F.Paste")
			(net "GND")
			(options
				(clearance outline)
				(anchor circle)
			)
			(primitives
				(gr_poly
					(pts
						(arc
							(start -0.1778 -0.2794)
							(mid -0.249642 -0.249642)
							(end -0.2794 -0.1778)
						)
						(arc
							(start -0.2794 0.1778)
							(mid -0.249642 0.249642)
							(end -0.1778 0.2794)
						)
						(arc
							(start 0.1778 0.2794)
							(mid 0.249642 0.249642)
							(end 0.2794 0.1778)
						)
						(arc
							(start 0.2794 -0.1778)
							(mid 0.249642 -0.249642)
							(end 0.1778 -0.2794)
						)
					)
					(width 0)
					(fill yes)
				)
			)
		)
	)
	(footprint ""
		(layer "F.Cu")
		(at 458.5335 -272.535142 180)
		(property "Reference" "R368"
			(at 0 0 180)
			(layer "F.SilkS")
			(hide yes)
			(effects
				(font
					(size 1.27 1.27)
				)
			)
		)
		(property "Value" "1KR2F-3-GP"
			(at 0.064008 -3.993896 180)
			(unlocked yes)
			(layer "F.Fab")
			(hide yes)
			(effects
				(font
					(size 1.016 1.016)
					(thickness 0.1524)
				)
			)
		)
		(property "Device Type" "R402H16"
			(at 0.064008 -5.517896 180)
			(unlocked yes)
			(layer "F.Fab")
			(hide yes)
			(effects
				(font
					(size 1.016 1.016)
					(thickness 0.1524)
				)
			)
		)
		(duplicate_pad_numbers_are_jumpers no)
		(fp_line
			(start 0.508 -0.9398)
			(end -0.508 -0.9398)
			(stroke
				(width 0.1524)
				(type default)
			)
			(layer "F.SilkS")
		)
		(fp_line
			(start -0.508 -0.9398)
			(end -0.508 0.9398)
			(stroke
				(width 0.1524)
				(type default)
			)
			(layer "F.SilkS")
		)
		(fp_rect
			(start -0.508 0.9398)
			(end 0.508 -0.9398)
			(stroke
				(width 0)
				(type default)
			)
			(fill no)
			(layer "F.CrtYd")
		)
		(fp_rect
			(start -0.508 0.9398)
			(end 0.508 -0.9398)
			(stroke
				(width 0)
				(type default)
			)
			(fill no)
			(layer "F.Fab")
		)
		(pad "1" smd custom
			(at 0 -0.4445 180)
			(size 0.1397 0.1397)
			(layers "F.Cu" "F.Mask" "F.Paste")
			(net "P3V3_STBY_A")
			(options
				(clearance outline)
				(anchor circle)
			)
			(primitives
				(gr_poly
					(pts
						(arc
							(start -0.1778 -0.2794)
							(mid -0.249642 -0.249642)
							(end -0.2794 -0.1778)
						)
						(arc
							(start -0.2794 0.1778)
							(mid -0.249642 0.249642)
							(end -0.1778 0.2794)
						)
						(arc
							(start 0.1778 0.2794)
							(mid 0.249642 0.249642)
							(end 0.2794 0.1778)
						)
						(arc
							(start 0.2794 -0.1778)
							(mid 0.249642 -0.249642)
							(end 0.1778 -0.2794)
						)
					)
					(width 0)
					(fill yes)
				)
			)
		)
		(pad "2" smd custom
			(at 0 0.4445 180)
			(size 0.1397 0.1397)
			(layers "F.Cu" "F.Mask" "F.Paste")
			(net "SW_PWR_R_HDD10")
			(options
				(clearance outline)
				(anchor circle)
			)
			(primitives
				(gr_poly
					(pts
						(arc
							(start -0.1778 -0.2794)
							(mid -0.249642 -0.249642)
							(end -0.2794 -0.1778)
						)
						(arc
							(start -0.2794 0.1778)
							(mid -0.249642 0.249642)
							(end -0.1778 0.2794)
						)
						(arc
							(start 0.1778 0.2794)
							(mid 0.249642 0.249642)
							(end 0.2794 0.1778)
						)
						(arc
							(start 0.2794 -0.1778)
							(mid 0.249642 -0.249642)
							(end 0.1778 -0.2794)
						)
					)
					(width 0)
					(fill yes)
				)
			)
		)
	)
	(footprint ""
		(layer "F.Cu")
		(at 95.563436 -44.219368 90)
		(property "Reference" "C376"
			(at 0 0 90)
			(layer "F.SilkS")
			(hide yes)
			(effects
				(font
					(size 1.27 1.27)
				)
			)
		)
		(property "Value" "SCD01U16V1KX-GP"
			(at -2.8321 -1.7399 90)
			(unlocked yes)
			(layer "F.Fab")
			(hide yes)
			(effects
				(font
					(size 1.016 1.016)
					(thickness 0.1524)
				)
			)
		)
		(property "Device Type" "C0201H13"
			(at -2.8321 -3.2639 90)
			(unlocked yes)
			(layer "F.Fab")
			(hide yes)
			(effects
				(font
					(size 1.016 1.016)
					(thickness 0.1524)
				)
			)
		)
		(duplicate_pad_numbers_are_jumpers no)
		(fp_rect
			(start -0.2794 0.6477)
			(end 0.2794 -0.6477)
			(stroke
				(width 0)
				(type default)
			)
			(fill no)
			(layer "F.CrtYd")
		)
		(fp_rect
			(start -0.2794 0.6477)
			(end 0.2794 -0.6477)
			(stroke
				(width 0)
				(type default)
			)
			(fill no)
			(layer "F.Fab")
		)
		(pad "1" smd custom
			(at 0 -0.2794 90)
			(size 0.0762 0.0762)
			(layers "F.Cu" "F.Mask" "F.Paste")
			(net "SAS_HDD_RX_N26")
			(options
				(clearance outline)
				(anchor circle)
			)
			(primitives
				(gr_poly
					(pts
						(arc
							(start 0.1524 -0.127)
							(mid 0.137521 -0.162921)
							(end 0.1016 -0.1778)
						)
						(arc
							(start -0.1016 -0.1778)
							(mid -0.137521 -0.162921)
							(end -0.1524 -0.127)
						)
						(arc
							(start -0.1524 0.127)
							(mid -0.137521 0.162921)
							(end -0.1016 0.1778)
						)
						(arc
							(start 0.1016 0.1778)
							(mid 0.137521 0.162921)
							(end 0.1524 0.127)
						)
					)
					(width 0)
					(fill yes)
				)
			)
		)
		(pad "2" smd custom
			(at 0 0.2794 90)
			(size 0.0762 0.0762)
			(layers "F.Cu" "F.Mask" "F.Paste")
			(net "PHY_SCC_A_TO_DRV_A_26_DN")
			(options
				(clearance outline)
				(anchor circle)
			)
			(primitives
				(gr_poly
					(pts
						(arc
							(start 0.1524 -0.127)
							(mid 0.137521 -0.162921)
							(end 0.1016 -0.1778)
						)
						(arc
							(start -0.1016 -0.1778)
							(mid -0.137521 -0.162921)
							(end -0.1524 -0.127)
						)
						(arc
							(start -0.1524 0.127)
							(mid -0.137521 0.162921)
							(end -0.1016 0.1778)
						)
						(arc
							(start 0.1016 0.1778)
							(mid 0.137521 0.162921)
							(end 0.1524 0.127)
						)
					)
					(width 0)
					(fill yes)
				)
			)
		)
	)
	(footprint ""
		(layer "F.Cu")
		(at 258.367276 -261.35076)
		(property "Reference" "R60"
			(at 0 0 0)
			(layer "F.SilkS")
			(hide yes)
			(effects
				(font
					(size 1.27 1.27)
				)
			)
		)
		(property "Value" "4K7R2F-GP"
			(at 0.064008 -3.993896 0)
			(unlocked yes)
			(layer "F.Fab")
			(hide yes)
			(effects
				(font
					(size 1.016 1.016)
					(thickness 0.1524)
				)
			)
		)
		(property "Device Type" "R402H16"
			(at 0.064008 -5.517896 0)
			(unlocked yes)
			(layer "F.Fab")
			(hide yes)
			(effects
				(font
					(size 1.016 1.016)
					(thickness 0.1524)
				)
			)
		)
		(duplicate_pad_numbers_are_jumpers no)
		(fp_line
			(start -0.508 -0.9398)
			(end -0.508 0.9398)
			(stroke
				(width 0.1524)
				(type default)
			)
			(layer "F.SilkS")
		)
		(fp_line
			(start 0.508 -0.9398)
			(end -0.508 -0.9398)
			(stroke
				(width 0.1524)
				(type default)
			)
			(layer "F.SilkS")
		)
		(fp_rect
			(start -0.508 0.9398)
			(end 0.508 -0.9398)
			(stroke
				(width 0)
				(type default)
			)
			(fill no)
			(layer "F.CrtYd")
		)
		(fp_rect
			(start -0.508 0.9398)
			(end 0.508 -0.9398)
			(stroke
				(width 0)
				(type default)
			)
			(fill no)
			(layer "F.Fab")
		)
		(pad "1" smd custom
			(at 0 -0.4445)
			(size 0.1397 0.1397)
			(layers "F.Cu" "F.Mask" "F.Paste")
			(net "P3V3_STBY_A")
			(options
				(clearance outline)
				(anchor circle)
			)
			(primitives
				(gr_poly
					(pts
						(arc
							(start -0.1778 -0.2794)
							(mid -0.249642 -0.249642)
							(end -0.2794 -0.1778)
						)
						(arc
							(start -0.2794 0.1778)
							(mid -0.249642 0.249642)
							(end -0.1778 0.2794)
						)
						(arc
							(start 0.1778 0.2794)
							(mid 0.249642 0.249642)
							(end 0.2794 0.1778)
						)
						(arc
							(start 0.2794 -0.1778)
							(mid 0.249642 -0.249642)
							(end 0.1778 -0.2794)
						)
					)
					(width 0)
					(fill yes)
				)
			)
		)
		(pad "2" smd custom
			(at 0 0.4445)
			(size 0.1397 0.1397)
			(layers "F.Cu" "F.Mask" "F.Paste")
			(net "IO_EXP6_A0")
			(options
				(clearance outline)
				(anchor circle)
			)
			(primitives
				(gr_poly
					(pts
						(arc
							(start -0.1778 -0.2794)
							(mid -0.249642 -0.249642)
							(end -0.2794 -0.1778)
						)
						(arc
							(start -0.2794 0.1778)
							(mid -0.249642 0.249642)
							(end -0.1778 0.2794)
						)
						(arc
							(start 0.1778 0.2794)
							(mid 0.249642 0.249642)
							(end 0.2794 0.1778)
						)
						(arc
							(start 0.2794 -0.1778)
							(mid 0.249642 -0.249642)
							(end 0.1778 -0.2794)
						)
					)
					(width 0)
					(fill yes)
				)
			)
		)
	)
	(footprint ""
		(layer "F.Cu")
		(at 18.415 -242.25377)
		(property "Reference" "R196"
			(at 0 0 0)
			(layer "F.SilkS")
			(hide yes)
			(effects
				(font
					(size 1.27 1.27)
				)
			)
		)
		(property "Value" "91R3F-1-GP"
			(at -0.0254 -2.5146 0)
			(unlocked yes)
			(layer "F.Fab")
			(hide yes)
			(effects
				(font
					(size 1.016 1.016)
					(thickness 0.1524)
				)
			)
		)
		(property "Device Type" "R603H22"
			(at -0.0254 -4.0386 0)
			(unlocked yes)
			(layer "F.Fab")
			(hide yes)
			(effects
				(font
					(size 1.016 1.016)
					(thickness 0.1524)
				)
			)
		)
		(duplicate_pad_numbers_are_jumpers no)
		(fp_line
			(start -0.4826 0)
			(end -0.2032 0)
			(stroke
				(width 0.2032)
				(type default)
			)
			(layer "F.SilkS")
		)
		(fp_line
			(start 0.2032 0)
			(end 0.4826 0)
			(stroke
				(width 0.2032)
				(type default)
			)
			(layer "F.SilkS")
		)
		(fp_rect
			(start -0.5842 1.3335)
			(end 0.5842 -1.3335)
			(stroke
				(width 0)
				(type default)
			)
			(fill no)
			(layer "F.CrtYd")
		)
		(fp_rect
			(start -0.5842 1.3335)
			(end 0.5842 -1.3335)
			(stroke
				(width 0)
				(type default)
			)
			(fill no)
			(layer "F.Fab")
		)
		(pad "1" smd custom
			(at 0 -0.762)
			(size 0.2159 0.2159)
			(layers "F.Cu" "F.Mask" "F.Paste")
			(net "P5V_A_1")
			(options
				(clearance outline)
				(anchor circle)
			)
			(primitives
				(gr_poly
					(pts
						(arc
							(start -0.3302 -0.4318)
							(mid -0.402042 -0.402042)
							(end -0.4318 -0.3302)
						)
						(arc
							(start -0.4318 0.3302)
							(mid -0.402042 0.402042)
							(end -0.3302 0.4318)
						)
						(arc
							(start 0.3302 0.4318)
							(mid 0.402042 0.402042)
							(end 0.4318 0.3302)
						)
						(arc
							(start 0.4318 -0.3302)
							(mid 0.402042 -0.402042)
							(end 0.3302 -0.4318)
						)
					)
					(width 0)
					(fill yes)
				)
			)
		)
		(pad "2" smd custom
			(at 0 0.762)
			(size 0.2159 0.2159)
			(layers "F.Cu" "F.Mask" "F.Paste")
			(net "DRV_ACT_0")
			(options
				(clearance outline)
				(anchor circle)
			)
			(primitives
				(gr_poly
					(pts
						(arc
							(start -0.3302 -0.4318)
							(mid -0.402042 -0.402042)
							(end -0.4318 -0.3302)
						)
						(arc
							(start -0.4318 0.3302)
							(mid -0.402042 0.402042)
							(end -0.3302 0.4318)
						)
						(arc
							(start 0.3302 0.4318)
							(mid 0.402042 0.402042)
							(end 0.4318 0.3302)
						)
						(arc
							(start 0.4318 -0.3302)
							(mid 0.402042 -0.402042)
							(end 0.3302 -0.4318)
						)
					)
					(width 0)
					(fill yes)
				)
			)
		)
	)
	(footprint ""
		(layer "F.Cu")
		(at 373.622062 -294.392858 180)
		(property "Reference" "R301"
			(at 0 0 180)
			(layer "F.SilkS")
			(hide yes)
			(effects
				(font
					(size 1.27 1.27)
				)
			)
		)
		(property "Value" "91R3F-1-GP"
			(at -0.0254 -2.5146 180)
			(unlocked yes)
			(layer "F.Fab")
			(hide yes)
			(effects
				(font
					(size 1.016 1.016)
					(thickness 0.1524)
				)
			)
		)
		(property "Device Type" "R603H22"
			(at -0.0254 -4.0386 180)
			(unlocked yes)
			(layer "F.Fab")
			(hide yes)
			(effects
				(font
					(size 1.016 1.016)
					(thickness 0.1524)
				)
			)
		)
		(duplicate_pad_numbers_are_jumpers no)
		(fp_line
			(start 0.2032 0)
			(end 0.4826 0)
			(stroke
				(width 0.2032)
				(type default)
			)
			(layer "F.SilkS")
		)
		(fp_line
			(start -0.4826 0)
			(end -0.2032 0)
			(stroke
				(width 0.2032)
				(type default)
			)
			(layer "F.SilkS")
		)
		(fp_rect
			(start -0.5842 1.3335)
			(end 0.5842 -1.3335)
			(stroke
				(width 0)
				(type default)
			)
			(fill no)
			(layer "F.CrtYd")
		)
		(fp_rect
			(start -0.5842 1.3335)
			(end 0.5842 -1.3335)
			(stroke
				(width 0)
				(type default)
			)
			(fill no)
			(layer "F.Fab")
		)
		(pad "1" smd custom
			(at 0 -0.762 180)
			(size 0.2159 0.2159)
			(layers "F.Cu" "F.Mask" "F.Paste")
			(net "P5V_B")
			(options
				(clearance outline)
				(anchor circle)
			)
			(primitives
				(gr_poly
					(pts
						(arc
							(start -0.3302 -0.4318)
							(mid -0.402042 -0.402042)
							(end -0.4318 -0.3302)
						)
						(arc
							(start -0.4318 0.3302)
							(mid -0.402042 0.402042)
							(end -0.3302 0.4318)
						)
						(arc
							(start 0.3302 0.4318)
							(mid 0.402042 0.402042)
							(end 0.4318 0.3302)
						)
						(arc
							(start 0.4318 -0.3302)
							(mid 0.402042 -0.402042)
							(end 0.3302 -0.4318)
						)
					)
					(width 0)
					(fill yes)
				)
			)
		)
		(pad "2" smd custom
			(at 0 0.762 180)
			(size 0.2159 0.2159)
			(layers "F.Cu" "F.Mask" "F.Paste")
			(net "DRV_ACT_32")
			(options
				(clearance outline)
				(anchor circle)
			)
			(primitives
				(gr_poly
					(pts
						(arc
							(start -0.3302 -0.4318)
							(mid -0.402042 -0.402042)
							(end -0.4318 -0.3302)
						)
						(arc
							(start -0.4318 0.3302)
							(mid -0.402042 0.402042)
							(end -0.3302 0.4318)
						)
						(arc
							(start 0.3302 0.4318)
							(mid 0.402042 0.402042)
							(end 0.4318 0.3302)
						)
						(arc
							(start 0.4318 -0.3302)
							(mid 0.402042 -0.402042)
							(end 0.3302 -0.4318)
						)
					)
					(width 0)
					(fill yes)
				)
			)
		)
	)
	(footprint ""
		(layer "F.Cu")
		(at 80.624934 -18.50517 -90)
		(property "Reference" "R34"
			(at 0 0 270)
			(layer "F.SilkS")
			(hide yes)
			(effects
				(font
					(size 1.27 1.27)
				)
			)
		)
		(property "Value" "4K7R2F-GP"
			(at 0.064008 -3.993896 270)
			(unlocked yes)
			(layer "F.Fab")
			(hide yes)
			(effects
				(font
					(size 1.016 1.016)
					(thickness 0.1524)
				)
			)
		)
		(property "Device Type" "R402H16"
			(at 0.064008 -5.517896 270)
			(unlocked yes)
			(layer "F.Fab")
			(hide yes)
			(effects
				(font
					(size 1.016 1.016)
					(thickness 0.1524)
				)
			)
		)
		(duplicate_pad_numbers_are_jumpers no)
		(fp_line
			(start -0.508 -0.9398)
			(end -0.508 0.9398)
			(stroke
				(width 0.1524)
				(type default)
			)
			(layer "F.SilkS")
		)
		(fp_line
			(start 0.508 -0.9398)
			(end -0.508 -0.9398)
			(stroke
				(width 0.1524)
				(type default)
			)
			(layer "F.SilkS")
		)
		(fp_rect
			(start -0.508 0.9398)
			(end 0.508 -0.9398)
			(stroke
				(width 0)
				(type default)
			)
			(fill no)
			(layer "F.CrtYd")
		)
		(fp_rect
			(start -0.508 0.9398)
			(end 0.508 -0.9398)
			(stroke
				(width 0)
				(type default)
			)
			(fill no)
			(layer "F.Fab")
		)
		(pad "1" smd custom
			(at 0 -0.4445 270)
			(size 0.1397 0.1397)
			(layers "F.Cu" "F.Mask" "F.Paste")
			(net "IO_EXP10_A1")
			(options
				(clearance outline)
				(anchor circle)
			)
			(primitives
				(gr_poly
					(pts
						(arc
							(start -0.1778 -0.2794)
							(mid -0.249642 -0.249642)
							(end -0.2794 -0.1778)
						)
						(arc
							(start -0.2794 0.1778)
							(mid -0.249642 0.249642)
							(end -0.1778 0.2794)
						)
						(arc
							(start 0.1778 0.2794)
							(mid 0.249642 0.249642)
							(end 0.2794 0.1778)
						)
						(arc
							(start 0.2794 -0.1778)
							(mid 0.249642 -0.249642)
							(end 0.1778 -0.2794)
						)
					)
					(width 0)
					(fill yes)
				)
			)
		)
		(pad "2" smd custom
			(at 0 0.4445 270)
			(size 0.1397 0.1397)
			(layers "F.Cu" "F.Mask" "F.Paste")
			(net "GND")
			(options
				(clearance outline)
				(anchor circle)
			)
			(primitives
				(gr_poly
					(pts
						(arc
							(start -0.1778 -0.2794)
							(mid -0.249642 -0.249642)
							(end -0.2794 -0.1778)
						)
						(arc
							(start -0.2794 0.1778)
							(mid -0.249642 0.249642)
							(end -0.1778 0.2794)
						)
						(arc
							(start 0.1778 0.2794)
							(mid 0.249642 0.249642)
							(end 0.2794 0.1778)
						)
						(arc
							(start 0.2794 -0.1778)
							(mid 0.249642 -0.249642)
							(end 0.1778 -0.2794)
						)
					)
					(width 0)
					(fill yes)
				)
			)
		)
	)
)
